(kicad_pcb
	(version 20260206)
	(generator "pcbnew")
	(generator_version "10.0")
	(general
		(thickness 1.6)
		(legacy_teardrops no)
	)
	(paper "A4")
	(title_block
		(title "03242023_DA0F0TMBIJ0_F0T_Motherboard_J_brd_V01_OCP.brd")
		(comment 1 "Grand Teton / footprint 3039 of 6105 (U2), pads 3791-3900 of 4677")
	)
	(layers
		(0 "F.Cu" signal "TOP")
		(4 "In1.Cu" signal "GND")
		(6 "In2.Cu" signal "IN1")
		(8 "In3.Cu" signal "GND1")
		(10 "In4.Cu" signal "IN2")
		(12 "In5.Cu" signal "GND2")
		(14 "In6.Cu" signal "IN3")
		(16 "In7.Cu" signal "GND3")
		(18 "In8.Cu" signal "VCC")
		(20 "In9.Cu" signal "VCC1")
		(22 "In10.Cu" signal "GND4")
		(24 "In11.Cu" signal "IN4")
		(26 "In12.Cu" signal "GND5")
		(28 "In13.Cu" signal "IN5")
		(30 "In14.Cu" signal "GND6")
		(32 "In15.Cu" signal "IN6")
		(34 "In16.Cu" signal "GND7")
		(2 "B.Cu" signal "BOTTOM")
		(9 "F.Adhes" user "F.Adhesive")
		(11 "B.Adhes" user "B.Adhesive")
		(13 "F.Paste" user "Package Geometry/Pastemask Top")
		(15 "B.Paste" user "Package Geometry/Pastemask Bottom")
		(5 "F.SilkS" user "Ref Des/Silkscreen Top")
		(7 "B.SilkS" user "Ref Des/Silkscreen Bottom")
		(1 "F.Mask" user "Board Geometry/Soldermask Top")
		(3 "B.Mask" user "Board Geometry/Soldermask Bottom")
		(17 "Dwgs.User" user "User.Drawings")
		(19 "Cmts.User" user "User.Comments")
		(21 "Eco1.User" user "User.Eco1")
		(23 "Eco2.User" user "User.Eco2")
		(25 "Edge.Cuts" user "Board Geometry/Outline")
		(27 "Margin" user)
		(31 "F.CrtYd" user "Package Geometry/Place Bound Top")
		(29 "B.CrtYd" user "Package Geometry/Place Bound Bottom")
		(35 "F.Fab" user "Ref Des/Assembly Top")
		(33 "B.Fab" user "Ref Des/Assembly Bottom")
	)
	(footprint ""
		(layer "F.Cu")
		(at 359.870248 -251.76988 90)
		(property "Reference" "U2"
			(at -74.416158 -44.488608 0)
			(unlocked yes)
			(layer "F.SilkS")
			(effects
				(font
					(size 1.6002 1.1938)
					(thickness 0.1524)
				)
				(justify left)
			)
		)
		(property "Value" ""
			(at 0 0 90)
			(layer "F.Fab")
			(effects
				(font
					(size 1.27 1.27)
				)
			)
		)
		(duplicate_pad_numbers_are_jumpers no)
		(pad "EL31" smd circle
			(at -13.008356 24.614886 270)
			(size 0.4318 0.4318)
			(layers "F.Cu" "F.Mask" "F.Paste")
			(net "M_E_CPU0_SB_DQ<9>")
		)
		(pad "EL33" smd circle
			(at -11.380724 24.614886 270)
			(size 0.4318 0.4318)
			(layers "F.Cu" "F.Mask" "F.Paste")
			(net "GND")
		)
		(pad "EL35" smd circle
			(at -9.752838 24.614886 270)
			(size 0.4318 0.4318)
			(layers "F.Cu" "F.Mask" "F.Paste")
			(net "M_E_CPU0_SB_CB<0>")
		)
		(pad "EL37" smd circle
			(at -8.124952 24.614886 270)
			(size 0.4318 0.4318)
			(layers "F.Cu" "F.Mask" "F.Paste")
			(net "M_E_CPU0_SB_CB<5>")
		)
		(pad "EL39" smd circle
			(at -6.49732 24.614886 270)
			(size 0.4318 0.4318)
			(layers "F.Cu" "F.Mask" "F.Paste")
			(net "GND")
		)
		(pad "EL41" smd circle
			(at -4.869434 24.614886 270)
			(size 0.4318 0.4318)
			(layers "F.Cu" "F.Mask" "F.Paste")
			(net "M_E_CPU0_SB_CS_N<3>")
		)
		(pad "EL43" smd circle
			(at -3.241802 24.614886 270)
			(size 0.4318 0.4318)
			(layers "F.Cu" "F.Mask" "F.Paste")
			(net "M_E_CPU0_SB_CA<4>")
		)
		(pad "EL45" smd circle
			(at -1.613916 24.614886 270)
			(size 0.4318 0.4318)
			(layers "F.Cu" "F.Mask" "F.Paste")
			(net "GND")
		)
		(pad "EL48" smd circle
			(at 2.427732 24.724868 270)
			(size 0.4318 0.4318)
			(layers "F.Cu" "F.Mask" "F.Paste")
			(net "M_E_CPU0_SA_CA<3>")
		)
		(pad "EL50" smd circle
			(at 4.055618 24.724868 270)
			(size 0.4318 0.4318)
			(layers "F.Cu" "F.Mask" "F.Paste")
			(net "M_E_CPU0_SA_CS_N<3>")
		)
		(pad "EL52" smd circle
			(at 5.68325 24.724868 270)
			(size 0.4318 0.4318)
			(layers "F.Cu" "F.Mask" "F.Paste")
			(net "GND")
		)
		(pad "EL54" smd circle
			(at 7.311136 24.724868 270)
			(size 0.4318 0.4318)
			(layers "F.Cu" "F.Mask" "F.Paste")
			(net "M_E_CPU0_SA_CB<4>")
		)
		(pad "EL56" smd circle
			(at 8.939022 24.724868 270)
			(size 0.4318 0.4318)
			(layers "F.Cu" "F.Mask" "F.Paste")
			(net "M_E_CPU0_SA_CB<1>")
		)
		(pad "EL58" smd circle
			(at 10.566654 24.724868 270)
			(size 0.4318 0.4318)
			(layers "F.Cu" "F.Mask" "F.Paste")
			(net "GND")
		)
		(pad "EL60" smd circle
			(at 12.19454 24.724868 270)
			(size 0.4318 0.4318)
			(layers "F.Cu" "F.Mask" "F.Paste")
			(net "M_E_CPU0_SA_DQ<28>")
		)
		(pad "EL62" smd circle
			(at 13.822426 24.724868 270)
			(size 0.4318 0.4318)
			(layers "F.Cu" "F.Mask" "F.Paste")
			(net "M_E_CPU0_SA_DQ<25>")
		)
		(pad "EL64" smd circle
			(at 15.450058 24.724868 270)
			(size 0.4318 0.4318)
			(layers "F.Cu" "F.Mask" "F.Paste")
			(net "GND")
		)
		(pad "EL66" smd circle
			(at 17.07769 24.724868 270)
			(size 0.4318 0.4318)
			(layers "F.Cu" "F.Mask" "F.Paste")
			(net "M_E_CPU0_SA_DQ<22>")
		)
		(pad "EL68" smd circle
			(at 18.705576 24.724868 270)
			(size 0.4318 0.4318)
			(layers "F.Cu" "F.Mask" "F.Paste")
			(net "M_E_CPU0_SA_DQS_DP<2>")
		)
		(pad "EL70" smd circle
			(at 20.333462 24.724868 270)
			(size 0.4318 0.4318)
			(layers "F.Cu" "F.Mask" "F.Paste")
			(net "GND")
		)
		(pad "EL72" smd circle
			(at 21.961094 24.724868 270)
			(size 0.4318 0.4318)
			(layers "F.Cu" "F.Mask" "F.Paste")
			(net "GND")
		)
		(pad "EL74" smd circle
			(at 23.58898 24.724868 270)
			(size 0.4318 0.4318)
			(layers "F.Cu" "F.Mask" "F.Paste")
			(net "M_E_CPU0_SA_DQ<4>")
		)
		(pad "EL76" smd circle
			(at 25.216612 24.724868 270)
			(size 0.4318 0.4318)
			(layers "F.Cu" "F.Mask" "F.Paste")
			(net "GND")
		)
		(pad "EL78" smd circle
			(at 26.844498 24.724868 270)
			(size 0.4318 0.4318)
			(layers "F.Cu" "F.Mask" "F.Paste")
			(net "M_E_CPU0_SA_DQ<0>")
		)
		(pad "EL80" smd circle
			(at 28.472384 24.724868 270)
			(size 0.4318 0.4318)
			(layers "F.Cu" "F.Mask" "F.Paste")
			(net "GND")
		)
		(pad "EL82" smd circle
			(at 30.100016 24.724868 270)
			(size 0.4318 0.4318)
			(layers "F.Cu" "F.Mask" "F.Paste")
			(net "GND")
		)
		(pad "EL84" smd circle
			(at 31.727902 24.724868 270)
			(size 0.4318 0.4318)
			(layers "F.Cu" "F.Mask" "F.Paste")
			(net "Net_700")
		)
		(pad "EL86" smd oval
			(at 33.355534 24.724868 315)
			(size 0.381 0.4826)
			(drill
				(offset 0 -0.0508)
			)
			(layers "F.Cu" "F.Mask" "F.Paste")
			(net "GND")
		)
		(pad "EL88" smd oval
			(at 34.98342 24.724868 315)
			(size 0.381 0.4826)
			(drill
				(offset 0 -0.0508)
			)
			(layers "F.Cu" "F.Mask" "F.Paste")
			(net "Net_658")
		)
		(pad "EM4" smd oval
			(at -34.98342 25.084532 225)
			(size 0.381 0.4826)
			(drill
				(offset 0 -0.0508)
			)
			(layers "F.Cu" "F.Mask" "F.Paste")
			(net "M_G_CPU0_SB_DQ<31>")
		)
		(pad "EM6" smd oval
			(at -33.355534 25.084532 225)
			(size 0.381 0.4826)
			(drill
				(offset 0 -0.0508)
			)
			(layers "F.Cu" "F.Mask" "F.Paste")
			(net "M_G_CPU0_SB_DQS_DN<8>")
		)
		(pad "EM8" smd circle
			(at -31.727902 25.084532 270)
			(size 0.4318 0.4318)
			(layers "F.Cu" "F.Mask" "F.Paste")
			(net "GND")
		)
		(pad "EM10" smd circle
			(at -30.100016 25.084532 270)
			(size 0.4318 0.4318)
			(layers "F.Cu" "F.Mask" "F.Paste")
			(net "M_F_CPU0_SB_DQ<21>")
		)
		(pad "EM12" smd circle
			(at -28.472384 25.084532 270)
			(size 0.4318 0.4318)
			(layers "F.Cu" "F.Mask" "F.Paste")
			(net "M_F_CPU0_SB_DQS_DN<2>")
		)
		(pad "EM14" smd circle
			(at -26.844498 25.084532 270)
			(size 0.4318 0.4318)
			(layers "F.Cu" "F.Mask" "F.Paste")
			(net "M_F_CPU0_SB_DQ<16>")
		)
		(pad "EM16" smd circle
			(at -25.216612 25.084532 270)
			(size 0.4318 0.4318)
			(layers "F.Cu" "F.Mask" "F.Paste")
			(net "M_E_CPU0_SB_DQ<29>")
		)
		(pad "EM18" smd circle
			(at -23.58898 25.084532 270)
			(size 0.4318 0.4318)
			(layers "F.Cu" "F.Mask" "F.Paste")
			(net "M_E_CPU0_SB_DQS_DP<3>")
		)
		(pad "EM20" smd circle
			(at -21.961094 25.084532 270)
			(size 0.4318 0.4318)
			(layers "F.Cu" "F.Mask" "F.Paste")
			(net "M_E_CPU0_SB_DQ<24>")
		)
		(pad "EM22" smd circle
			(at -20.333462 25.084532 270)
			(size 0.4318 0.4318)
			(layers "F.Cu" "F.Mask" "F.Paste")
			(net "M_E_CPU0_SB_DQ<21>")
		)
		(pad "EM24" smd circle
			(at -18.705576 25.084532 270)
			(size 0.4318 0.4318)
			(layers "F.Cu" "F.Mask" "F.Paste")
			(net "M_E_CPU0_SB_DQS_DP<2>")
		)
		(pad "EM26" smd circle
			(at -17.07769 25.084532 270)
			(size 0.4318 0.4318)
			(layers "F.Cu" "F.Mask" "F.Paste")
			(net "M_E_CPU0_SB_DQ<16>")
		)
		(pad "EM28" smd circle
			(at -15.450058 25.084532 270)
			(size 0.4318 0.4318)
			(layers "F.Cu" "F.Mask" "F.Paste")
			(net "M_E_CPU0_SB_DQ<13>")
		)
		(pad "EM30" smd circle
			(at -13.822426 25.084532 270)
			(size 0.4318 0.4318)
			(layers "F.Cu" "F.Mask" "F.Paste")
			(net "M_E_CPU0_SB_DQS_DP<1>")
		)
		(pad "EM32" smd circle
			(at -12.19454 25.084532 270)
			(size 0.4318 0.4318)
			(layers "F.Cu" "F.Mask" "F.Paste")
			(net "M_E_CPU0_SB_DQ<8>")
		)
		(pad "EM34" smd circle
			(at -10.566654 25.084532 270)
			(size 0.4318 0.4318)
			(layers "F.Cu" "F.Mask" "F.Paste")
			(net "M_E_CPU0_SB_CB<1>")
		)
		(pad "EM36" smd circle
			(at -8.939022 25.084532 270)
			(size 0.4318 0.4318)
			(layers "F.Cu" "F.Mask" "F.Paste")
			(net "M_E_CPU0_SB_DQS_DP<9>")
		)
		(pad "EM38" smd circle
			(at -7.311136 25.084532 270)
			(size 0.4318 0.4318)
			(layers "F.Cu" "F.Mask" "F.Paste")
			(net "M_E_CPU0_SB_CB<4>")
		)
		(pad "EM40" smd circle
			(at -5.68325 25.084532 270)
			(size 0.4318 0.4318)
			(layers "F.Cu" "F.Mask" "F.Paste")
			(net "M_E_CPU0_SB_CS_N<2>")
		)
		(pad "EM42" smd circle
			(at -4.055618 25.084532 270)
			(size 0.4318 0.4318)
			(layers "F.Cu" "F.Mask" "F.Paste")
			(net "GND")
		)
		(pad "EM44" smd circle
			(at -2.427732 25.084532 270)
			(size 0.4318 0.4318)
			(layers "F.Cu" "F.Mask" "F.Paste")
			(net "M_E_CPU0_SB_CA<2>")
		)
		(pad "EM47" smd circle
			(at 1.613916 25.194514 270)
			(size 0.4318 0.4318)
			(layers "F.Cu" "F.Mask" "F.Paste")
			(net "M_E_CPU0_SA_CA<4>")
		)
		(pad "EM49" smd circle
			(at 3.241802 25.194514 270)
			(size 0.4318 0.4318)
			(layers "F.Cu" "F.Mask" "F.Paste")
			(net "GND")
		)
		(pad "EM51" smd circle
			(at 4.869434 25.194514 270)
			(size 0.4318 0.4318)
			(layers "F.Cu" "F.Mask" "F.Paste")
			(net "M_E_CPU0_SA_CS_N<2>")
		)
		(pad "EM53" smd circle
			(at 6.49732 25.194514 270)
			(size 0.4318 0.4318)
			(layers "F.Cu" "F.Mask" "F.Paste")
			(net "M_E_CPU0_SA_CB<5>")
		)
		(pad "EM55" smd circle
			(at 8.124952 25.194514 270)
			(size 0.4318 0.4318)
			(layers "F.Cu" "F.Mask" "F.Paste")
			(net "M_E_CPU0_SA_DQS_DN<4>")
		)
		(pad "EM57" smd circle
			(at 9.752838 25.194514 270)
			(size 0.4318 0.4318)
			(layers "F.Cu" "F.Mask" "F.Paste")
			(net "M_E_CPU0_SA_CB<0>")
		)
		(pad "EM59" smd circle
			(at 11.380724 25.194514 270)
			(size 0.4318 0.4318)
			(layers "F.Cu" "F.Mask" "F.Paste")
			(net "M_E_CPU0_SA_DQ<29>")
		)
		(pad "EM61" smd circle
			(at 13.008356 25.194514 270)
			(size 0.4318 0.4318)
			(layers "F.Cu" "F.Mask" "F.Paste")
			(net "M_E_CPU0_SA_DQS_DP<3>")
		)
		(pad "EM63" smd circle
			(at 14.635988 25.194514 270)
			(size 0.4318 0.4318)
			(layers "F.Cu" "F.Mask" "F.Paste")
			(net "M_E_CPU0_SA_DQ<24>")
		)
		(pad "EM65" smd circle
			(at 16.263874 25.194514 270)
			(size 0.4318 0.4318)
			(layers "F.Cu" "F.Mask" "F.Paste")
			(net "M_E_CPU0_SA_DQ<21>")
		)
		(pad "EM67" smd circle
			(at 17.89176 25.194514 270)
			(size 0.4318 0.4318)
			(layers "F.Cu" "F.Mask" "F.Paste")
			(net "M_E_CPU0_SA_DQS_DP<7>")
		)
		(pad "EM69" smd circle
			(at 19.519392 25.194514 270)
			(size 0.4318 0.4318)
			(layers "F.Cu" "F.Mask" "F.Paste")
			(net "M_E_CPU0_SA_DQ<17>")
		)
		(pad "EM71" smd circle
			(at 21.147278 25.194514 270)
			(size 0.4318 0.4318)
			(layers "F.Cu" "F.Mask" "F.Paste")
			(net "M_E_CPU0_SA_DQ<16>")
		)
		(pad "EM73" smd circle
			(at 22.77491 25.194514 270)
			(size 0.4318 0.4318)
			(layers "F.Cu" "F.Mask" "F.Paste")
			(net "GND")
		)
		(pad "EM75" smd circle
			(at 24.402796 25.194514 270)
			(size 0.4318 0.4318)
			(layers "F.Cu" "F.Mask" "F.Paste")
			(net "M_E_CPU0_SA_DQS_DN<5>")
		)
		(pad "EM77" smd circle
			(at 26.030682 25.194514 270)
			(size 0.4318 0.4318)
			(layers "F.Cu" "F.Mask" "F.Paste")
			(net "M_E_CPU0_SA_DQ<1>")
		)
		(pad "EM79" smd circle
			(at 27.658314 25.194514 270)
			(size 0.4318 0.4318)
			(layers "F.Cu" "F.Mask" "F.Paste")
			(net "GND")
		)
		(pad "EM81" smd circle
			(at 29.2862 25.194514 270)
			(size 0.4318 0.4318)
			(layers "F.Cu" "F.Mask" "F.Paste")
			(net "GND")
		)
		(pad "EM83" smd circle
			(at 30.914086 25.194514 270)
			(size 0.4318 0.4318)
			(layers "F.Cu" "F.Mask" "F.Paste")
			(net "GND")
		)
		(pad "EM85" smd oval
			(at 32.541718 25.194514 315)
			(size 0.381 0.4826)
			(drill
				(offset 0 -0.0508)
			)
			(layers "F.Cu" "F.Mask" "F.Paste")
			(net "Net_676")
		)
		(pad "EM87" smd oval
			(at 34.169604 25.194514 315)
			(size 0.381 0.4826)
			(drill
				(offset 0 -0.0508)
			)
			(layers "F.Cu" "F.Mask" "F.Paste")
			(net "Net_684")
		)
		(pad "EN5" smd oval
			(at -34.169604 25.554686 225)
			(size 0.381 0.4826)
			(drill
				(offset 0 -0.0508)
			)
			(layers "F.Cu" "F.Mask" "F.Paste")
			(net "M_G_CPU0_SB_DQS_DP<8>")
		)
		(pad "EN7" smd oval
			(at -32.541718 25.554686 225)
			(size 0.381 0.4826)
			(drill
				(offset 0 -0.0508)
			)
			(layers "F.Cu" "F.Mask" "F.Paste")
			(net "M_G_CPU0_SB_DQS_DP<3>")
		)
		(pad "EN9" smd circle
			(at -30.914086 25.554686 270)
			(size 0.4318 0.4318)
			(layers "F.Cu" "F.Mask" "F.Paste")
			(net "GND")
		)
		(pad "EN11" smd circle
			(at -29.2862 25.554686 270)
			(size 0.4318 0.4318)
			(layers "F.Cu" "F.Mask" "F.Paste")
			(net "GND")
		)
		(pad "EN13" smd circle
			(at -27.658314 25.554686 270)
			(size 0.4318 0.4318)
			(layers "F.Cu" "F.Mask" "F.Paste")
			(net "GND")
		)
		(pad "EN15" smd circle
			(at -26.030682 25.554686 270)
			(size 0.4318 0.4318)
			(layers "F.Cu" "F.Mask" "F.Paste")
			(net "GND")
		)
		(pad "EN17" smd circle
			(at -24.402796 25.554686 270)
			(size 0.4318 0.4318)
			(layers "F.Cu" "F.Mask" "F.Paste")
			(net "GND")
		)
		(pad "EN19" smd circle
			(at -22.77491 25.554686 270)
			(size 0.4318 0.4318)
			(layers "F.Cu" "F.Mask" "F.Paste")
			(net "GND")
		)
		(pad "EN21" smd circle
			(at -21.147278 25.554686 270)
			(size 0.4318 0.4318)
			(layers "F.Cu" "F.Mask" "F.Paste")
			(net "GND")
		)
		(pad "EN23" smd circle
			(at -19.519392 25.554686 270)
			(size 0.4318 0.4318)
			(layers "F.Cu" "F.Mask" "F.Paste")
			(net "GND")
		)
		(pad "EN25" smd circle
			(at -17.89176 25.554686 270)
			(size 0.4318 0.4318)
			(layers "F.Cu" "F.Mask" "F.Paste")
			(net "GND")
		)
		(pad "EN27" smd circle
			(at -16.263874 25.554686 270)
			(size 0.4318 0.4318)
			(layers "F.Cu" "F.Mask" "F.Paste")
			(net "GND")
		)
		(pad "EN29" smd circle
			(at -14.635988 25.554686 270)
			(size 0.4318 0.4318)
			(layers "F.Cu" "F.Mask" "F.Paste")
			(net "GND")
		)
		(pad "EN31" smd circle
			(at -13.008356 25.554686 270)
			(size 0.4318 0.4318)
			(layers "F.Cu" "F.Mask" "F.Paste")
			(net "GND")
		)
		(pad "EN33" smd circle
			(at -11.380724 25.554686 270)
			(size 0.4318 0.4318)
			(layers "F.Cu" "F.Mask" "F.Paste")
			(net "GND")
		)
		(pad "EN35" smd circle
			(at -9.752838 25.554686 270)
			(size 0.4318 0.4318)
			(layers "F.Cu" "F.Mask" "F.Paste")
			(net "GND")
		)
		(pad "EN37" smd circle
			(at -8.124952 25.554686 270)
			(size 0.4318 0.4318)
			(layers "F.Cu" "F.Mask" "F.Paste")
			(net "GND")
		)
		(pad "EN39" smd circle
			(at -6.49732 25.554686 270)
			(size 0.4318 0.4318)
			(layers "F.Cu" "F.Mask" "F.Paste")
			(net "GND")
		)
		(pad "EN41" smd circle
			(at -4.869434 25.554686 270)
			(size 0.4318 0.4318)
			(layers "F.Cu" "F.Mask" "F.Paste")
			(net "GND")
		)
		(pad "EN43" smd circle
			(at -3.241802 25.554686 270)
			(size 0.4318 0.4318)
			(layers "F.Cu" "F.Mask" "F.Paste")
			(net "GND")
		)
		(pad "EN45" smd oval
			(at -1.613916 25.554686 270)
			(size 0.381 0.4826)
			(drill
				(offset 0 -0.0508)
			)
			(layers "F.Cu" "F.Mask" "F.Paste")
			(net "GND")
		)
		(pad "EN48" smd circle
			(at 2.427732 25.664414 270)
			(size 0.4318 0.4318)
			(layers "F.Cu" "F.Mask" "F.Paste")
			(net "GND")
		)
		(pad "EN50" smd circle
			(at 4.055618 25.664414 270)
			(size 0.4318 0.4318)
			(layers "F.Cu" "F.Mask" "F.Paste")
			(net "GND")
		)
		(pad "EN52" smd circle
			(at 5.68325 25.664414 270)
			(size 0.4318 0.4318)
			(layers "F.Cu" "F.Mask" "F.Paste")
			(net "GND")
		)
		(pad "EN54" smd circle
			(at 7.311136 25.664414 270)
			(size 0.4318 0.4318)
			(layers "F.Cu" "F.Mask" "F.Paste")
			(net "GND")
		)
		(pad "EN56" smd circle
			(at 8.939022 25.664414 270)
			(size 0.4318 0.4318)
			(layers "F.Cu" "F.Mask" "F.Paste")
			(net "GND")
		)
		(pad "EN58" smd circle
			(at 10.566654 25.664414 270)
			(size 0.4318 0.4318)
			(layers "F.Cu" "F.Mask" "F.Paste")
			(net "GND")
		)
		(pad "EN60" smd circle
			(at 12.19454 25.664414 270)
			(size 0.4318 0.4318)
			(layers "F.Cu" "F.Mask" "F.Paste")
			(net "GND")
		)
		(pad "EN62" smd circle
			(at 13.822426 25.664414 270)
			(size 0.4318 0.4318)
			(layers "F.Cu" "F.Mask" "F.Paste")
			(net "GND")
		)
		(pad "EN64" smd circle
			(at 15.450058 25.664414 270)
			(size 0.4318 0.4318)
			(layers "F.Cu" "F.Mask" "F.Paste")
			(net "GND")
		)
		(pad "EN66" smd circle
			(at 17.07769 25.664414 270)
			(size 0.4318 0.4318)
			(layers "F.Cu" "F.Mask" "F.Paste")
			(net "GND")
		)
		(pad "EN68" smd circle
			(at 18.705576 25.664414 270)
			(size 0.4318 0.4318)
			(layers "F.Cu" "F.Mask" "F.Paste")
			(net "M_E_CPU0_SA_DQS_DN<7>")
		)
		(pad "EN70" smd circle
			(at 20.333462 25.664414 270)
			(size 0.4318 0.4318)
			(layers "F.Cu" "F.Mask" "F.Paste")
			(net "M_E_CPU0_SA_DQ<18>")
		)
		(pad "EN72" smd circle
			(at 21.961094 25.664414 270)
			(size 0.4318 0.4318)
			(layers "F.Cu" "F.Mask" "F.Paste")
			(net "GND")
		)
		(pad "EN74" smd circle
			(at 23.58898 25.664414 270)
			(size 0.4318 0.4318)
			(layers "F.Cu" "F.Mask" "F.Paste")
			(net "M_E_CPU0_SA_DQS_DP<5>")
		)
		(pad "EN76" smd circle
			(at 25.216612 25.664414 270)
			(size 0.4318 0.4318)
			(layers "F.Cu" "F.Mask" "F.Paste")
			(net "M_E_CPU0_SA_DQS_DP<0>")
		)
		(pad "EN78" smd circle
			(at 26.844498 25.664414 270)
			(size 0.4318 0.4318)
			(layers "F.Cu" "F.Mask" "F.Paste")
			(net "GND")
		)
		(pad "EN80" smd circle
			(at 28.472384 25.664414 270)
			(size 0.4318 0.4318)
			(layers "F.Cu" "F.Mask" "F.Paste")
			(net "GND")
		)
		(pad "EN82" smd circle
			(at 30.100016 25.664414 270)
			(size 0.4318 0.4318)
			(layers "F.Cu" "F.Mask" "F.Paste")
			(net "GND")
		)
	)
)
